FILE_TYPE = CONNECTIVITY;
{Allegro Design Entry HDL 17.4-2019 S026 (4007227) 1/17/2022}
"PAGE_NUMBER" = 270;
0"NC";
END.
